(kicad_pcb
	(version 20260206)
	(generator "pcbnew")
	(generator_version "10.0")
	(general
		(thickness 1.6)
		(legacy_teardrops no)
	)
	(paper "A4")
	(title_block
		(title "v2-tray-backplane — ms_tbp_v2.brd")
		(comment 1 "Open CloudServer (Microsoft) / footprints 37-41 of 164")
	)
	(layers
		(0 "F.Cu" signal "TOP")
		(4 "In1.Cu" signal "LYR2")
		(6 "In2.Cu" signal "LYR3")
		(8 "In3.Cu" signal "LYR4")
		(10 "In4.Cu" signal "LYR5")
		(12 "In5.Cu" signal "LYR6")
		(14 "In6.Cu" signal "LYR7")
		(2 "B.Cu" signal "BOTTOM")
		(9 "F.Adhes" user "F.Adhesive")
		(11 "B.Adhes" user "B.Adhesive")
		(13 "F.Paste" user "Package Geometry/Pastemask Top")
		(15 "B.Paste" user "Package Geometry/Pastemask Bottom")
		(5 "F.SilkS" user "Ref Des/Silkscreen Top")
		(7 "B.SilkS" user "Ref Des/Silkscreen Bottom")
		(1 "F.Mask" user "Board Geometry/Soldermask Top")
		(3 "B.Mask" user "Board Geometry/Soldermask Bottom")
		(17 "Dwgs.User" user "User.Drawings")
		(19 "Cmts.User" user "User.Comments")
		(21 "Eco1.User" user "User.Eco1")
		(23 "Eco2.User" user "User.Eco2")
		(25 "Edge.Cuts" user "Board Geometry/Outline")
		(27 "Margin" user)
		(31 "F.CrtYd" user "Package Geometry/Place Bound Top")
		(29 "B.CrtYd" user "Package Geometry/Place Bound Bottom")
		(35 "F.Fab" user "Ref Des/Assembly Top")
		(33 "B.Fab" user "Ref Des/Assembly Bottom")
	)
	(footprint ""
		(layer "F.Cu")
		(at -46.774001 9.233002 -90)
		(property "Reference" "C19"
			(at 0.713638 -1.447701 0)
			(unlocked yes)
			(layer "F.SilkS")
			(effects
				(font
					(size 0.762 0.5334)
					(thickness 0.1016)
				)
			)
		)
		(property "Value" ""
			(at 0 0 270)
			(layer "F.Fab")
			(effects
				(font
					(size 1.27 1.27)
				)
			)
		)
		(duplicate_pad_numbers_are_jumpers no)
		(fp_poly
			(pts
				(xy -0.9993 0.503999) (xy -0.9993 -0.504) (xy 0.999299 -0.504) (xy 0.999299 0.503999)
			)
			(stroke
				(width 0)
				(type default)
			)
			(fill no)
			(layer "F.CrtYd")
		)
		(fp_line
			(start -0.499999 0.249999)
			(end -0.499999 -0.25)
			(stroke
				(width 0.1)
				(type default)
			)
			(layer "F.Fab")
		)
		(fp_line
			(start 0.499999 0.249999)
			(end -0.499999 0.249999)
			(stroke
				(width 0.1)
				(type default)
			)
			(layer "F.Fab")
		)
		(fp_line
			(start -0.499999 -0.25)
			(end 0.499999 -0.25)
			(stroke
				(width 0.1)
				(type default)
			)
			(layer "F.Fab")
		)
		(fp_line
			(start 0.499999 -0.25)
			(end 0.499999 0.249999)
			(stroke
				(width 0.1)
				(type default)
			)
			(layer "F.Fab")
		)
		(pad "1" smd rect
			(at -0.4572 0)
			(size 0.508 0.5842)
			(layers "F.Cu" "F.Mask" "F.Paste")
			(net "P3V3_40G_B2_VCC_TX")
		)
		(pad "2" smd rect
			(at 0.4572 0)
			(size 0.508 0.5842)
			(layers "F.Cu" "F.Mask" "F.Paste")
			(net "GND")
		)
	)
	(footprint ""
		(layer "F.Cu")
		(at -75.292801 6.591402)
		(property "Reference" "R48"
			(at 2.902801 0.050698 0)
			(unlocked yes)
			(layer "F.SilkS")
			(effects
				(font
					(size 0.762 0.5334)
					(thickness 0.1016)
				)
			)
		)
		(property "Value" ""
			(at 0 0 0)
			(layer "F.Fab")
			(effects
				(font
					(size 1.27 1.27)
				)
			)
		)
		(duplicate_pad_numbers_are_jumpers no)
		(fp_line
			(start 0 -0.381)
			(end 0 0.381)
			(stroke
				(width 0.127)
				(type default)
			)
			(layer "F.SilkS")
		)
		(fp_poly
			(pts
				(xy 1.255601 0.656399) (xy -1.255601 0.656399) (xy -1.255601 -0.6564) (xy 1.255601 -0.6564)
			)
			(stroke
				(width 0)
				(type default)
			)
			(fill no)
			(layer "F.CrtYd")
		)
		(fp_line
			(start -0.800001 -0.4)
			(end -0.800001 0.399999)
			(stroke
				(width 0.1)
				(type default)
			)
			(layer "F.Fab")
		)
		(fp_line
			(start -0.800001 0.399999)
			(end 0.800001 0.399999)
			(stroke
				(width 0.1)
				(type default)
			)
			(layer "F.Fab")
		)
		(fp_line
			(start 0.800001 -0.4)
			(end -0.800001 -0.4)
			(stroke
				(width 0.1)
				(type default)
			)
			(layer "F.Fab")
		)
		(fp_line
			(start 0.800001 0.399999)
			(end 0.800001 -0.4)
			(stroke
				(width 0.1)
				(type default)
			)
			(layer "F.Fab")
		)
		(pad "1" smd rect
			(at -0.650001 0)
			(size 0.7112 0.8128)
			(layers "F.Cu" "F.Mask" "F.Paste")
			(net "P3V3_B2_QSFP")
		)
		(pad "2" smd rect
			(at 0.650001 0 180)
			(size 0.7112 0.8128)
			(layers "F.Cu" "F.Mask" "F.Paste")
			(net "ETH10G_B2_TX_DIS")
		)
	)
	(footprint ""
		(layer "F.Cu")
		(at -411.66 -5.840001 180)
		(property "Reference" "U1"
			(at -20.627 -12.228101 0)
			(unlocked yes)
			(layer "F.SilkS")
			(effects
				(font
					(size 0.762 0.5334)
					(thickness 0.1016)
				)
			)
		)
		(property "Value" ""
			(at 0 0 180)
			(layer "F.Fab")
			(effects
				(font
					(size 1.27 1.27)
				)
			)
		)
		(duplicate_pad_numbers_are_jumpers no)
		(fp_poly
			(pts
				(xy -42.28 0.499999) (xy -42.28 -11.000001)
				(arc
					(start -1.3038 -11.000001)
					(mid 0 -11.99996)
					(end 1.303799 -11.000001)
				)
				(xy 11.799999 -11.000001) (xy 11.799999 0.499999)
			)
			(stroke
				(width 0)
				(type default)
			)
			(fill no)
			(layer "B.CrtYd")
		)
		(fp_poly
			(pts
				(xy -42.28 0.499999) (xy -42.28 -11.000001)
				(arc
					(start -1.3038 -11.000001)
					(mid 0 -11.99996)
					(end 1.303799 -11.000001)
				)
				(xy 11.799999 -11.000001) (xy 11.799999 0.499999)
			)
			(stroke
				(width 0)
				(type default)
			)
			(fill no)
			(layer "F.CrtYd")
		)
		(fp_line
			(start 10.800001 0)
			(end -41.280002 0)
			(stroke
				(width 0.1)
				(type default)
			)
			(layer "F.Fab")
		)
		(fp_line
			(start 10.800001 -11.000001)
			(end 10.800001 0)
			(stroke
				(width 0.1)
				(type default)
			)
			(layer "F.Fab")
		)
		(fp_line
			(start -41.280002 0)
			(end -41.280002 -11.000001)
			(stroke
				(width 0.1)
				(type default)
			)
			(layer "F.Fab")
		)
		(fp_line
			(start -41.280002 -11.000001)
			(end 10.800001 -11.000001)
			(stroke
				(width 0.1)
				(type default)
			)
			(layer "F.Fab")
		)
		(fp_text user "S6"
			(at 8.66552 -9.572899 90)
			(unlocked yes)
			(layer "F.SilkS")
			(effects
				(font
					(size 0.762 0.5334)
					(thickness 0.1016)
				)
				(justify left)
			)
		)
		(fp_text user "S1"
			(at 2.31552 -9.572899 90)
			(unlocked yes)
			(layer "F.SilkS")
			(effects
				(font
					(size 0.762 0.5334)
					(thickness 0.1016)
				)
				(justify left)
			)
		)
		(fp_text user "*"
			(at 1.344 -8.716551 0)
			(unlocked yes)
			(layer "F.SilkS")
			(effects
				(font
					(size 0.381 0.381)
					(thickness 0.381)
				)
			)
		)
		(fp_text user "P13-P16"
			(at -4.625 -9.942101 0)
			(unlocked yes)
			(layer "F.SilkS")
			(effects
				(font
					(size 0.762 0.5334)
					(thickness 0.1016)
				)
			)
		)
		(fp_text user "P9-P12"
			(at -16.309 -9.942101 0)
			(unlocked yes)
			(layer "F.SilkS")
			(effects
				(font
					(size 0.762 0.5334)
					(thickness 0.1016)
				)
			)
		)
		(fp_text user "P5-P8"
			(at -26.52996 -9.586501 0)
			(unlocked yes)
			(layer "F.SilkS")
			(effects
				(font
					(size 0.762 0.5334)
					(thickness 0.1016)
				)
			)
		)
		(fp_text user "P1-P4"
			(at -35.4352 -9.632221 0)
			(unlocked yes)
			(layer "F.SilkS")
			(effects
				(font
					(size 0.762 0.5334)
					(thickness 0.1016)
				)
			)
		)
		(fp_text user "S7"
			(at 7.948 -9.307101 0)
			(unlocked yes)
			(layer "B.SilkS")
			(effects
				(font
					(size 0.762 0.5334)
					(thickness 0.1016)
				)
				(justify left mirror)
			)
		)
		(fp_text user "S12"
			(at 1.979 -9.561101 0)
			(unlocked yes)
			(layer "B.SilkS")
			(effects
				(font
					(size 0.762 0.5334)
					(thickness 0.1016)
				)
				(justify left mirror)
			)
		)
		(fp_text user "P17-P20"
			(at -5.133 -10.323101 0)
			(unlocked yes)
			(layer "B.SilkS")
			(effects
				(font
					(size 0.762 0.5334)
					(thickness 0.1016)
				)
				(justify mirror)
			)
		)
		(fp_text user "P21-P24"
			(at -15.547 -10.196101 0)
			(unlocked yes)
			(layer "B.SilkS")
			(effects
				(font
					(size 0.762 0.5334)
					(thickness 0.1016)
				)
				(justify mirror)
			)
		)
		(fp_text user "P25-P28"
			(at -26.12102 -9.586501 0)
			(unlocked yes)
			(layer "B.SilkS")
			(effects
				(font
					(size 0.762 0.5334)
					(thickness 0.1016)
				)
				(justify mirror)
			)
		)
		(fp_text user "P29-P32"
			(at -35.87462 -9.632221 0)
			(unlocked yes)
			(layer "B.SilkS")
			(effects
				(font
					(size 0.762 0.5334)
					(thickness 0.1016)
				)
				(justify mirror)
			)
		)
		(pad "P1-P4" smd rect
			(at -35.56 -4.650001 180)
			(size 9.4488 6.2992)
			(layers "F.Cu" "F.Mask" "F.Paste")
			(net "GND")
		)
		(pad "P5-P8" smd rect
			(at -25.4 -4.650001 180)
			(size 9.4488 6.2992)
			(layers "F.Cu" "F.Mask" "F.Paste")
			(net "GND")
		)
		(pad "P9-P12" smd rect
			(at -15.24 -4.650001 180)
			(size 9.4488 6.2992)
			(layers "F.Cu" "F.Mask" "F.Paste")
			(net "P12V")
		)
		(pad "P13-P16" smd rect
			(at -5.08 -4.650001 180)
			(size 9.4488 6.2992)
			(layers "F.Cu" "F.Mask" "F.Paste")
			(net "P12V")
		)
		(pad "P17-P20" smd rect
			(at -5.08 -4.650001 180)
			(size 9.4488 6.2992)
			(layers "F.Cu" "F.Mask" "F.Paste")
			(net "P12V")
		)
		(pad "P21-P24" smd rect
			(at -15.24 -4.650001 180)
			(size 9.4488 6.2992)
			(layers "F.Cu" "F.Mask" "F.Paste")
			(net "P12V")
		)
		(pad "P25-P28" smd rect
			(at -25.4 -4.650001 180)
			(size 9.4488 6.2992)
			(layers "F.Cu" "F.Mask" "F.Paste")
			(net "GND")
		)
		(pad "P29-P32" smd rect
			(at -35.56 -4.650001 180)
			(size 9.4488 6.2992)
			(layers "F.Cu" "F.Mask" "F.Paste")
			(net "GND")
		)
		(pad "S1" smd rect
			(at 2.230001 -4 180)
			(size 0.8128 5.0038)
			(layers "F.Cu" "F.Mask" "F.Paste")
			(net "SERIAL_B1_TX1")
		)
		(pad "S2" smd rect
			(at 3.500001 -4 180)
			(size 0.8128 5.0038)
			(layers "F.Cu" "F.Mask" "F.Paste")
			(net "SERIAL_B1_RX1")
		)
		(pad "S3" smd rect
			(at 4.770001 -4 180)
			(size 0.8128 5.0038)
			(layers "F.Cu" "F.Mask" "F.Paste")
			(net "BLADE_B1_EN1")
		)
		(pad "S4" smd rect
			(at 6.040001 -4 180)
			(size 0.8128 5.0038)
			(layers "F.Cu" "F.Mask" "F.Paste")
			(net "PSU_B1_ALERT_N")
		)
		(pad "S5" smd rect
			(at 7.310001 -4 180)
			(size 0.8128 5.0038)
			(layers "F.Cu" "F.Mask" "F.Paste")
			(net "SERIAL_B1_TX2")
		)
		(pad "S6" smd rect
			(at 8.580001 -4 180)
			(size 0.8128 5.0038)
			(layers "F.Cu" "F.Mask" "F.Paste")
			(net "SERIAL_B1_RX2")
		)
		(pad "S7" smd rect
			(at 8.580001 -4 180)
			(size 0.8128 5.0038)
			(layers "F.Cu" "F.Mask" "F.Paste")
			(net "SERIAL_B2_RX2")
		)
		(pad "S8" smd rect
			(at 7.310001 -4 180)
			(size 0.8128 5.0038)
			(layers "F.Cu" "F.Mask" "F.Paste")
			(net "SERIAL_B2_TX2")
		)
		(pad "S9" smd rect
			(at 6.040001 -4 180)
			(size 0.8128 5.0038)
			(layers "F.Cu" "F.Mask" "F.Paste")
			(net "PSU_B2_ALERT_N")
		)
		(pad "S10" smd rect
			(at 4.770001 -4 180)
			(size 0.8128 5.0038)
			(layers "F.Cu" "F.Mask" "F.Paste")
			(net "BLADE_B2_EN1")
		)
		(pad "S11" smd rect
			(at 3.500001 -4 180)
			(size 0.8128 5.0038)
			(layers "F.Cu" "F.Mask" "F.Paste")
			(net "SERIAL_B2_RX1")
		)
		(pad "S12" smd rect
			(at 2.230001 -4 180)
			(size 0.8128 5.0038)
			(layers "F.Cu" "F.Mask" "F.Paste")
			(net "SERIAL_B2_TX1")
		)
		(zone
			(layers "F.Cu" "B.Cu" "In1.Cu" "In2.Cu" "In3.Cu" "In4.Cu" "In5.Cu" "In6.Cu")
			(hatch none 0.5)
			(connect_pads
				(clearance 0)
			)
			(min_thickness 0.25)
			(keepout
				(tracks allowed)
				(vias not_allowed)
				(pads allowed)
				(copperpour not_allowed)
				(footprints allowed)
			)
			(placement
				(enabled no)
				(sheetname "")
			)
			(fill
				(thermal_gap 0.5)
				(thermal_bridge_width 0.5)
				(island_removal_mode 0)
			)
			(polygon
				(pts
					(xy -371.9 -5.790001) (xy -370.430001 -4.320002) (xy -370.430001 2.413) (xy -410.3878 2.413) (xy -410.759999 2.785199)
					(xy -410.759999 4.159999)
					(arc
						(start -410.759999 5.16)
						(mid -411.66 5.76)
						(end -412.56 5.16)
					)
					(xy -412.56 4.159999) (xy -422.409998 4.159999) (xy -422.409998 -4.320002) (xy -420.939999 -5.790001)
					(xy -413.509998 -5.790001) (xy -412.059999 -4.340001)
					(arc
						(start -412.059999 4.809998)
						(mid -411.66 5.209997)
						(end -411.26 4.809998)
					)
					(xy -411.26 -4.340001) (xy -409.810001 -5.790001)
				)
			)
		)
	)
	(footprint ""
		(layer "F.Cu")
		(at -344.551 4.7244 -90)
		(property "Reference" "R11"
			(at -0.05588 1.39954 90)
			(unlocked yes)
			(layer "F.SilkS")
			(effects
				(font
					(size 0.762 0.5334)
					(thickness 0.1016)
				)
			)
		)
		(property "Value" ""
			(at 0 0 270)
			(layer "F.Fab")
			(effects
				(font
					(size 1.27 1.27)
				)
			)
		)
		(duplicate_pad_numbers_are_jumpers no)
		(fp_line
			(start 0 -0.381)
			(end 0 0.381)
			(stroke
				(width 0.127)
				(type default)
			)
			(layer "F.SilkS")
		)
		(fp_poly
			(pts
				(xy 1.255601 0.6564) (xy -1.255601 0.6564) (xy -1.255601 -0.656399) (xy 1.255601 -0.656399)
			)
			(stroke
				(width 0)
				(type default)
			)
			(fill no)
			(layer "F.CrtYd")
		)
		(fp_line
			(start -0.800001 0.399999)
			(end 0.800001 0.399999)
			(stroke
				(width 0.1)
				(type default)
			)
			(layer "F.Fab")
		)
		(fp_line
			(start 0.800001 0.399999)
			(end 0.800001 -0.399999)
			(stroke
				(width 0.1)
				(type default)
			)
			(layer "F.Fab")
		)
		(fp_line
			(start -0.800001 -0.399999)
			(end -0.800001 0.399999)
			(stroke
				(width 0.1)
				(type default)
			)
			(layer "F.Fab")
		)
		(fp_line
			(start 0.800001 -0.399999)
			(end -0.800001 -0.399999)
			(stroke
				(width 0.1)
				(type default)
			)
			(layer "F.Fab")
		)
		(pad "1" smd rect
			(at -0.650001 0 270)
			(size 0.7112 0.8128)
			(layers "F.Cu" "F.Mask" "F.Paste")
			(net "UNNAMED_4_1X2HDR_I90_IO")
		)
		(pad "2" smd rect
			(at 0.650001 0 90)
			(size 0.7112 0.8128)
			(layers "F.Cu" "F.Mask" "F.Paste")
			(net "GND")
		)
	)
	(footprint ""
		(layer "F.Cu")
		(at -80.0862 1.8542)
		(property "Reference" "R43"
			(at -3.7338 -0.1651 0)
			(unlocked yes)
			(layer "F.SilkS")
			(effects
				(font
					(size 0.762 0.5334)
					(thickness 0.1016)
				)
			)
		)
		(property "Value" ""
			(at 0 0 0)
			(layer "F.Fab")
			(effects
				(font
					(size 1.27 1.27)
				)
			)
		)
		(duplicate_pad_numbers_are_jumpers no)
		(fp_line
			(start 0 -0.381)
			(end 0 0.381)
			(stroke
				(width 0.127)
				(type default)
			)
			(layer "F.SilkS")
		)
		(fp_poly
			(pts
				(xy 1.255601 0.6564) (xy -1.255601 0.6564) (xy -1.255601 -0.656399) (xy 1.255601 -0.656399)
			)
			(stroke
				(width 0)
				(type default)
			)
			(fill no)
			(layer "F.CrtYd")
		)
		(fp_line
			(start -0.800001 -0.399999)
			(end -0.800001 0.399999)
			(stroke
				(width 0.1)
				(type default)
			)
			(layer "F.Fab")
		)
		(fp_line
			(start -0.800001 0.399999)
			(end 0.800001 0.399999)
			(stroke
				(width 0.1)
				(type default)
			)
			(layer "F.Fab")
		)
		(fp_line
			(start 0.800001 -0.399999)
			(end -0.800001 -0.399999)
			(stroke
				(width 0.1)
				(type default)
			)
			(layer "F.Fab")
		)
		(fp_line
			(start 0.800001 0.399999)
			(end 0.800001 -0.399999)
			(stroke
				(width 0.1)
				(type default)
			)
			(layer "F.Fab")
		)
		(pad "1" smd rect
			(at -0.650001 0)
			(size 0.7112 0.8128)
			(layers "F.Cu" "F.Mask" "F.Paste")
			(net "ETH10G_B2_PRES_N")
		)
		(pad "2" smd rect
			(at 0.650001 0 180)
			(size 0.7112 0.8128)
			(layers "F.Cu" "F.Mask" "F.Paste")
			(net "ETH10G_B2_MOD_ABS")
		)
	)
)
